# NUC Computer Cluster Power Breakout HW — footprint library table
(fp_lib_table
  (version 7)
)
